# S9S_MB_2U (Grand Teton) — schematic netlist excerpt (pin names and nets, part order shuffled) for the footprints in the layout excerpt that follows; sources: Cadence DE-HDL packaged netlist, KiCad conversion of 03242023_DA0F0TMBIJ0_F0T_Motherboard_J_brd_V01_OCP.brd

R4295  Q_RES  100 1% CHIP  pkg 0402LF  page 124 : A = PWRGD_DRAMPWRGD_CPU0_AB_LVC1_R2 ; B = PWRGD_DRAMPWRGD_CPU0_AB_LVC1_R
R4674  Q_RES  10K 1% CHIP  pkg 0402LF  page 220 : A = FM_SLP_SUS_RSM_RST_N ; B = GND
PC1200_P1_4  Q_CAP  22UF 16V 20% X6S  pkg C0805  page 290 : A = SW_P12V_PVCCFA_EHV_FIVRA_CPU1_L ; B = GND

(kicad_pcb
	(version 20260206)
	(generator "pcbnew")
	(generator_version "10.0")
	(general
		(thickness 1.6)
		(legacy_teardrops no)
	)
	(paper "A4")
	(title_block
		(title "03242023_DA0F0TMBIJ0_F0T_Motherboard_J_brd_V01_OCP.brd")
		(comment 1 "Grand Teton / footprints 4527-4529 of 6105")
	)
	(layers
		(0 "F.Cu" signal "TOP")
		(4 "In1.Cu" signal "GND")
		(6 "In2.Cu" signal "IN1")
		(8 "In3.Cu" signal "GND1")
		(10 "In4.Cu" signal "IN2")
		(12 "In5.Cu" signal "GND2")
		(14 "In6.Cu" signal "IN3")
		(16 "In7.Cu" signal "GND3")
		(18 "In8.Cu" signal "VCC")
		(20 "In9.Cu" signal "VCC1")
		(22 "In10.Cu" signal "GND4")
		(24 "In11.Cu" signal "IN4")
		(26 "In12.Cu" signal "GND5")
		(28 "In13.Cu" signal "IN5")
		(30 "In14.Cu" signal "GND6")
		(32 "In15.Cu" signal "IN6")
		(34 "In16.Cu" signal "GND7")
		(2 "B.Cu" signal "BOTTOM")
		(9 "F.Adhes" user "F.Adhesive")
		(11 "B.Adhes" user "B.Adhesive")
		(13 "F.Paste" user "Package Geometry/Pastemask Top")
		(15 "B.Paste" user "Package Geometry/Pastemask Bottom")
		(5 "F.SilkS" user "Ref Des/Silkscreen Top")
		(7 "B.SilkS" user "Ref Des/Silkscreen Bottom")
		(1 "F.Mask" user "Board Geometry/Soldermask Top")
		(3 "B.Mask" user "Board Geometry/Soldermask Bottom")
		(17 "Dwgs.User" user "User.Drawings")
		(19 "Cmts.User" user "User.Comments")
		(21 "Eco1.User" user "User.Eco1")
		(23 "Eco2.User" user "User.Eco2")
		(25 "Edge.Cuts" user "Board Geometry/Outline")
		(27 "Margin" user)
		(31 "F.CrtYd" user "Package Geometry/Place Bound Top")
		(29 "B.CrtYd" user "Package Geometry/Place Bound Bottom")
		(35 "F.Fab" user "Ref Des/Assembly Top")
		(33 "B.Fab" user "Ref Des/Assembly Bottom")
	)
	(footprint ""
		(layer "B.Cu")
		(at 317.632588 -35.856672 -135)
		(property "Reference" "R4674"
			(at 0 0 45)
			(layer "B.SilkS")
			(hide yes)
			(effects
				(font
					(size 1.27 1.27)
				)
				(justify mirror)
			)
		)
		(property "Value" ""
			(at 0 0 45)
			(layer "B.Fab")
			(effects
				(font
					(size 1.27 1.27)
				)
				(justify mirror)
			)
		)
		(duplicate_pad_numbers_are_jumpers no)
		(fp_line
			(start 0.787389 0.406267)
			(end 0.787389 -0.406267)
			(stroke
				(width 0.1524)
				(type default)
			)
			(layer "B.SilkS")
		)
		(fp_line
			(start 0.787389 -0.406267)
			(end -0.787389 -0.406267)
			(stroke
				(width 0.1524)
				(type default)
			)
			(layer "B.SilkS")
		)
		(fp_line
			(start -0.787389 0.406267)
			(end 0.787389 0.406267)
			(stroke
				(width 0.1524)
				(type default)
			)
			(layer "B.SilkS")
		)
		(fp_line
			(start -0.787389 -0.406267)
			(end -0.787389 0.406267)
			(stroke
				(width 0.1524)
				(type default)
			)
			(layer "B.SilkS")
		)
		(fp_line
			(start 0.679446 0.30479)
			(end 0.679446 -0.305149)
			(stroke
				(width 0.1)
				(type default)
			)
			(layer "B.Fab")
		)
		(fp_line
			(start 0.120515 0.30479)
			(end 0.679446 0.30479)
			(stroke
				(width 0.1)
				(type default)
			)
			(layer "B.Fab")
		)
		(fp_line
			(start 0.120695 0.279466)
			(end 0.120515 0.30479)
			(stroke
				(width 0.1)
				(type default)
			)
			(layer "B.Fab")
		)
		(fp_line
			(start 0.679446 -0.305149)
			(end 0.120695 -0.304969)
			(stroke
				(width 0.1)
				(type default)
			)
			(layer "B.Fab")
		)
		(fp_line
			(start -0.120515 0.30479)
			(end -0.120335 0.279466)
			(stroke
				(width 0.1)
				(type default)
			)
			(layer "B.Fab")
		)
		(fp_line
			(start -0.120335 0.279466)
			(end 0.120695 0.279466)
			(stroke
				(width 0.1)
				(type default)
			)
			(layer "B.Fab")
		)
		(fp_line
			(start 0.120695 -0.279466)
			(end -0.120695 -0.279466)
			(stroke
				(width 0.1)
				(type default)
			)
			(layer "B.Fab")
		)
		(fp_line
			(start 0.120695 -0.304969)
			(end 0.120695 -0.279466)
			(stroke
				(width 0.1)
				(type default)
			)
			(layer "B.Fab")
		)
		(fp_line
			(start -0.679446 0.30479)
			(end -0.120515 0.30479)
			(stroke
				(width 0.1)
				(type default)
			)
			(layer "B.Fab")
		)
		(fp_line
			(start -0.120695 -0.279466)
			(end -0.120515 -0.30479)
			(stroke
				(width 0.1)
				(type default)
			)
			(layer "B.Fab")
		)
		(fp_line
			(start -0.120515 -0.30479)
			(end -0.679446 -0.30479)
			(stroke
				(width 0.1)
				(type default)
			)
			(layer "B.Fab")
		)
		(fp_line
			(start -0.679446 -0.30479)
			(end -0.679446 0.30479)
			(stroke
				(width 0.1)
				(type default)
			)
			(layer "B.Fab")
		)
		(pad "1" smd circle
			(at 0.40005 0 45)
			(size 0 0)
			(layers "B.Cu" "B.Mask" "B.Paste")
			(net "FM_SLP_SUS_RSM_RST_N")
		)
		(pad "2" smd circle
			(at -0.40005 0 45)
			(size 0 0)
			(layers "B.Cu" "B.Mask" "B.Paste")
			(net "GND")
		)
	)
	(footprint ""
		(layer "B.Cu")
		(at 44.821856 -353.567492 90)
		(property "Reference" "PC1200_P1_4"
			(at 0 0 90)
			(layer "B.SilkS")
			(hide yes)
			(effects
				(font
					(size 1.27 1.27)
				)
				(justify mirror)
			)
		)
		(property "Value" ""
			(at 0 0 90)
			(layer "B.Fab")
			(effects
				(font
					(size 1.27 1.27)
				)
				(justify mirror)
			)
		)
		(duplicate_pad_numbers_are_jumpers no)
		(fp_line
			(start 1.524 -0.762)
			(end -1.524 -0.762)
			(stroke
				(width 0.1524)
				(type default)
			)
			(layer "B.SilkS")
		)
		(fp_line
			(start -1.524 -0.762)
			(end -1.524 0.762)
			(stroke
				(width 0.1524)
				(type default)
			)
			(layer "B.SilkS")
		)
		(fp_line
			(start 1.524 0.762)
			(end 1.524 -0.762)
			(stroke
				(width 0.1524)
				(type default)
			)
			(layer "B.SilkS")
		)
		(fp_line
			(start -1.524 0.762)
			(end 1.524 0.762)
			(stroke
				(width 0.1524)
				(type default)
			)
			(layer "B.SilkS")
		)
		(fp_line
			(start 1.1049 -0.724916)
			(end 1.1049 0.724916)
			(stroke
				(width 0.1)
				(type default)
			)
			(layer "B.Fab")
		)
		(fp_line
			(start -1.1049 -0.724916)
			(end 1.1049 -0.724916)
			(stroke
				(width 0.1)
				(type default)
			)
			(layer "B.Fab")
		)
		(fp_line
			(start 1.1049 0.724916)
			(end -1.1049 0.724916)
			(stroke
				(width 0.1)
				(type default)
			)
			(layer "B.Fab")
		)
		(fp_line
			(start -1.1049 0.724916)
			(end -1.1049 -0.724916)
			(stroke
				(width 0.1)
				(type default)
			)
			(layer "B.Fab")
		)
		(pad "1" smd rect
			(at 0.889 0 90)
			(size 1.016 1.27)
			(layers "B.Cu" "B.Mask" "B.Paste")
			(net "SW_P12V_PVCCFA_EHV_FIVRA_CPU1_L")
		)
		(pad "2" smd rect
			(at -0.889 0 90)
			(size 1.016 1.27)
			(layers "B.Cu" "B.Mask" "B.Paste")
			(net "GND")
		)
	)
	(footprint ""
		(layer "B.Cu")
		(at 297.876468 -196.191378 -90)
		(property "Reference" "R4295"
			(at 0 0 90)
			(layer "B.SilkS")
			(hide yes)
			(effects
				(font
					(size 1.27 1.27)
				)
				(justify mirror)
			)
		)
		(property "Value" ""
			(at 0 0 90)
			(layer "B.Fab")
			(effects
				(font
					(size 1.27 1.27)
				)
				(justify mirror)
			)
		)
		(duplicate_pad_numbers_are_jumpers no)
		(fp_line
			(start -0.7874 0.4064)
			(end 0.7874 0.4064)
			(stroke
				(width 0.1524)
				(type default)
			)
			(layer "B.SilkS")
		)
		(fp_line
			(start 0.7874 0.4064)
			(end 0.7874 -0.4064)
			(stroke
				(width 0.1524)
				(type default)
			)
			(layer "B.SilkS")
		)
		(fp_line
			(start -0.7874 -0.4064)
			(end -0.7874 0.4064)
			(stroke
				(width 0.1524)
				(type default)
			)
			(layer "B.SilkS")
		)
		(fp_line
			(start 0.7874 -0.4064)
			(end -0.7874 -0.4064)
			(stroke
				(width 0.1524)
				(type default)
			)
			(layer "B.SilkS")
		)
		(fp_line
			(start -0.67945 0.3048)
			(end -0.120396 0.3048)
			(stroke
				(width 0.1)
				(type default)
			)
			(layer "B.Fab")
		)
		(fp_line
			(start -0.120396 0.3048)
			(end -0.120396 0.2794)
			(stroke
				(width 0.1)
				(type default)
			)
			(layer "B.Fab")
		)
		(fp_line
			(start 0.12065 0.3048)
			(end 0.67945 0.3048)
			(stroke
				(width 0.1)
				(type default)
			)
			(layer "B.Fab")
		)
		(fp_line
			(start 0.67945 0.3048)
			(end 0.67945 -0.305054)
			(stroke
				(width 0.1)
				(type default)
			)
			(layer "B.Fab")
		)
		(fp_line
			(start -0.120396 0.2794)
			(end 0.12065 0.2794)
			(stroke
				(width 0.1)
				(type default)
			)
			(layer "B.Fab")
		)
		(fp_line
			(start 0.12065 0.2794)
			(end 0.12065 0.3048)
			(stroke
				(width 0.1)
				(type default)
			)
			(layer "B.Fab")
		)
		(fp_line
			(start -0.12065 -0.2794)
			(end -0.12065 -0.3048)
			(stroke
				(width 0.1)
				(type default)
			)
			(layer "B.Fab")
		)
		(fp_line
			(start 0.12065 -0.2794)
			(end -0.12065 -0.2794)
			(stroke
				(width 0.1)
				(type default)
			)
			(layer "B.Fab")
		)
		(fp_line
			(start -0.67945 -0.3048)
			(end -0.67945 0.3048)
			(stroke
				(width 0.1)
				(type default)
			)
			(layer "B.Fab")
		)
		(fp_line
			(start -0.12065 -0.3048)
			(end -0.67945 -0.3048)
			(stroke
				(width 0.1)
				(type default)
			)
			(layer "B.Fab")
		)
		(fp_line
			(start 0.12065 -0.305054)
			(end 0.12065 -0.2794)
			(stroke
				(width 0.1)
				(type default)
			)
			(layer "B.Fab")
		)
		(fp_line
			(start 0.67945 -0.305054)
			(end 0.12065 -0.305054)
			(stroke
				(width 0.1)
				(type default)
			)
			(layer "B.Fab")
		)
		(pad "1" smd circle
			(at 0.40005 0 90)
			(size 0 0)
			(layers "B.Cu" "B.Mask" "B.Paste")
			(net "PWRGD_DRAMPWRGD_CPU0_AB_LVC1_R2")
		)
		(pad "2" smd circle
			(at -0.40005 0 90)
			(size 0 0)
			(layers "B.Cu" "B.Mask" "B.Paste")
			(net "PWRGD_DRAMPWRGD_CPU0_AB_LVC1_R")
		)
	)
)
